#ISCELL
  logical_power cad_note *
  *
#ISCELL
  pure_quanta quanta_title_block_c *
  *
#ISCELL
  logical_power universal_gnd *
  page84_i1
#CELL
  pure_quanta q_res *
  page84_i10
#ISCELL
  standard tap *
  page84_i100
#ISCELL
  standard tap *
  page84_i101
#ISCELL
  standard tap *
  page84_i102
#ISCELL
  standard tap *
  page84_i103
#ISCELL
  standard tap *
  page84_i104
#ISCELL
  standard tap *
  page84_i105
#ISCELL
  standard tap *
  page84_i106
#ISCELL
  standard tap *
  page84_i107
#ISCELL
  standard offpage *
  page84_i108
#ISCELL
  standard tap *
  page84_i109
#ISCELL
  standard tap *
  page84_i110
#ISCELL
  standard tap *
  page84_i111
#ISCELL
  standard tap *
  page84_i112
#ISCELL
  standard tap *
  page84_i113
#ISCELL
  standard tap *
  page84_i114
#ISCELL
  standard tap *
  page84_i115
#ISCELL
  standard tap *
  page84_i116
#ISCELL
  standard tap *
  page84_i117
#ISCELL
  standard tap *
  page84_i118
#ISCELL
  logical_power vcc_core *
  page84_i119
#ISCELL
  standard offpage *
  page84_i12
#ISCELL
  logical_power universal_gnd *
  page84_i120
#CELL
  pure_quanta q_cap *
  page84_i121
#CELL
  pure_quanta q_cap *
  page84_i122
#ISCELL
  logical_power vcc_core *
  page84_i123
#ISCELL
  standard offpage *
  page84_i124
#ISCELL
  standard tap *
  page84_i126
#ISCELL
  standard tap *
  page84_i127
#ISCELL
  standard tap *
  page84_i128
#ISCELL
  standard tap *
  page84_i129
#ISCELL
  logical_power vcc_core *
  page84_i13
#ISCELL
  standard tap *
  page84_i130
#ISCELL
  standard tap *
  page84_i131
#ISCELL
  standard tap *
  page84_i132
#ISCELL
  standard tap *
  page84_i133
#ISCELL
  standard tap *
  page84_i134
#ISCELL
  standard tap *
  page84_i135
#ISCELL
  standard tap *
  page84_i136
#ISCELL
  standard tap *
  page84_i137
#ISCELL
  standard tap *
  page84_i138
#ISCELL
  standard tap *
  page84_i139
#ISCELL
  standard offpage *
  page84_i14
#ISCELL
  standard tap *
  page84_i140
#ISCELL
  standard tap *
  page84_i141
#ISCELL
  standard tap *
  page84_i142
#ISCELL
  logical_power universal_gnd *
  page84_i143
#CELL
  pure_quanta q_cap *
  page84_i144
#ISCELL
  logical_power universal_gnd *
  page84_i145
#ISCELL
  standard tap *
  page84_i147
#ISCELL
  standard tap *
  page84_i148
#ISCELL
  standard tap *
  page84_i149
#ISCELL
  standard offpage *
  page84_i15
#ISCELL
  standard tap *
  page84_i150
#ISCELL
  standard tap *
  page84_i151
#ISCELL
  standard tap *
  page84_i152
#ISCELL
  standard tap *
  page84_i153
#ISCELL
  standard tap *
  page84_i154
#ISCELL
  standard tap *
  page84_i155
#ISCELL
  standard tap *
  page84_i156
#ISCELL
  standard tap *
  page84_i157
#ISCELL
  standard tap *
  page84_i158
#ISCELL
  standard tap *
  page84_i159
#ISCELL
  standard offpage *
  page84_i16
#ISCELL
  standard tap *
  page84_i160
#ISCELL
  standard tap *
  page84_i161
#ISCELL
  standard tap *
  page84_i162
#ISCELL
  standard tap *
  page84_i163
#ISCELL
  standard tap *
  page84_i164
#ISCELL
  standard offpage *
  page84_i165
#ISCELL
  standard offpage *
  page84_i166
#ISCELL
  standard offpage *
  page84_i167
#ISCELL
  standard tap *
  page84_i168
#ISCELL
  standard tap *
  page84_i169
#ISCELL
  standard offpage *
  page84_i17
#ISCELL
  standard tap *
  page84_i170
#ISCELL
  standard tap *
  page84_i171
#ISCELL
  standard tap *
  page84_i172
#ISCELL
  standard offpage *
  page84_i173
#ISCELL
  standard offpage *
  page84_i174
#ISCELL
  logical_power vcc_core *
  page84_i175
#ISCELL
  logical_power universal_gnd *
  page84_i176
#ISCELL
  standard offpage *
  page84_i177
#CELL
  pure_quanta sconn288_adr50017p130cc *
  page84_i178
#CELL
  pure_quanta sconn288_adr50017p130cc *
  page84_i179
#ISCELL
  standard offpage *
  page84_i18
#CELL
  pure_quanta sconn288_adr50017p130cc *
  page84_i180
#CELL
  pure_quanta q_res *
  page84_i182
#ISCELL
  standard offpage *
  page84_i183
#ISCELL
  standard offpage *
  page84_i19
#ISCELL
  standard offpage *
  page84_i2
#ISCELL
  standard offpage *
  page84_i20
#ISCELL
  standard offpage *
  page84_i21
#ISCELL
  standard offpage *
  page84_i22
#ISCELL
  standard offpage *
  page84_i23
#ISCELL
  standard tap *
  page84_i24
#ISCELL
  standard tap *
  page84_i25
#ISCELL
  standard tap *
  page84_i26
#ISCELL
  standard tap *
  page84_i27
#ISCELL
  standard tap *
  page84_i28
#ISCELL
  standard tap *
  page84_i29
#ISCELL
  standard offpage *
  page84_i3
#ISCELL
  standard tap *
  page84_i30
#ISCELL
  standard tap *
  page84_i31
#ISCELL
  standard tap *
  page84_i32
#ISCELL
  standard tap *
  page84_i33
#ISCELL
  standard tap *
  page84_i34
#ISCELL
  standard tap *
  page84_i35
#ISCELL
  standard tap *
  page84_i36
#ISCELL
  standard tap *
  page84_i37
#ISCELL
  standard tap *
  page84_i38
#ISCELL
  standard tap *
  page84_i39
#ISCELL
  standard offpage *
  page84_i4
#ISCELL
  standard tap *
  page84_i40
#ISCELL
  standard tap *
  page84_i41
#ISCELL
  standard tap *
  page84_i42
#ISCELL
  standard tap *
  page84_i43
#ISCELL
  standard tap *
  page84_i44
#ISCELL
  standard tap *
  page84_i45
#ISCELL
  standard tap *
  page84_i46
#ISCELL
  standard tap *
  page84_i47
#ISCELL
  standard tap *
  page84_i48
#ISCELL
  standard tap *
  page84_i49
#ISCELL
  standard tap *
  page84_i50
#ISCELL
  standard tap *
  page84_i51
#ISCELL
  standard tap *
  page84_i52
#ISCELL
  standard tap *
  page84_i53
#ISCELL
  standard tap *
  page84_i54
#ISCELL
  standard tap *
  page84_i55
#ISCELL
  standard tap *
  page84_i56
#ISCELL
  standard tap *
  page84_i57
#ISCELL
  standard tap *
  page84_i58
#ISCELL
  standard tap *
  page84_i59
#ISCELL
  standard offpage *
  page84_i6
#ISCELL
  standard tap *
  page84_i60
#ISCELL
  standard tap *
  page84_i61
#ISCELL
  standard tap *
  page84_i62
#ISCELL
  standard tap *
  page84_i63
#ISCELL
  standard tap *
  page84_i64
#ISCELL
  standard tap *
  page84_i65
#ISCELL
  standard tap *
  page84_i66
#ISCELL
  standard tap *
  page84_i67
#ISCELL
  standard tap *
  page84_i68
#ISCELL
  standard tap *
  page84_i69
#ISCELL
  standard offpage *
  page84_i7
#ISCELL
  standard tap *
  page84_i70
#ISCELL
  standard tap *
  page84_i71
#ISCELL
  standard tap *
  page84_i72
#ISCELL
  standard tap *
  page84_i73
#ISCELL
  standard tap *
  page84_i74
#ISCELL
  standard tap *
  page84_i75
#ISCELL
  standard tap *
  page84_i76
#ISCELL
  standard tap *
  page84_i77
#ISCELL
  standard tap *
  page84_i78
#ISCELL
  standard tap *
  page84_i79
#ISCELL
  standard offpage *
  page84_i8
#ISCELL
  standard tap *
  page84_i80
#ISCELL
  standard tap *
  page84_i81
#ISCELL
  standard tap *
  page84_i82
#ISCELL
  standard tap *
  page84_i83
#ISCELL
  standard tap *
  page84_i84
#ISCELL
  standard tap *
  page84_i85
#ISCELL
  standard tap *
  page84_i86
#ISCELL
  standard tap *
  page84_i87
#ISCELL
  standard tap *
  page84_i88
#ISCELL
  standard tap *
  page84_i89
#ISCELL
  standard offpage *
  page84_i9
#ISCELL
  standard tap *
  page84_i90
#ISCELL
  standard tap *
  page84_i91
#ISCELL
  standard tap *
  page84_i92
#ISCELL
  standard tap *
  page84_i93
#ISCELL
  standard tap *
  page84_i94
#ISCELL
  standard tap *
  page84_i95
#ISCELL
  standard tap *
  page84_i96
#ISCELL
  standard tap *
  page84_i97
#ISCELL
  standard tap *
  page84_i98
#ISCELL
  standard tap *
  page84_i99
